#ISCELL
  pure_quanta quanta_title_block_c *
  *
#ISCELL
  standard offpage *
  page453_i1
#ISCELL
  pure_quanta_power universal_gnd *
  page453_i18
#CELL
  pure_quanta q_res *
  page453_i19
#ISCELL
  standard offpage *
  page453_i2
#ISCELL
  pure_quanta_power universal_gnd *
  page453_i20
#ISCELL
  pure_quanta_power universal_gnd *
  page453_i21
#ISCELL
  pure_quanta_power p1v0 *
  page453_i22
#CELL
  pure_quanta q_cap *
  page453_i23
#ISCELL
  pure_quanta_power universal_gnd *
  page453_i24
#CELL
  pure_quanta q_res *
  page453_i3
#CELL
  pure_quanta q_res *
  page453_i4
#CELL
  pure_quanta m24m02drmn6tp *
  page453_i5
